(kicad_pcb
	(version 20260206)
	(generator "pcbnew")
	(generator_version "10.0")
	(general
		(thickness 1.6)
		(legacy_teardrops no)
	)
	(paper "A4")
	(title_block
		(title "pdpb — Lightning_PDPB_BRD.brd")
		(comment 1 "Lightning (Wiwynn / Facebook NVMe JBOF) / footprints 94-100 of 1140")
	)
	(layers
		(0 "F.Cu" signal "TOP")
		(4 "In1.Cu" signal "L2GND")
		(6 "In2.Cu" signal "L3")
		(8 "In3.Cu" signal "L4VCC")
		(10 "In4.Cu" signal "L5VCC")
		(12 "In5.Cu" signal "L6")
		(14 "In6.Cu" signal "L7GND")
		(2 "B.Cu" signal "BOTTOM")
		(9 "F.Adhes" user "F.Adhesive")
		(11 "B.Adhes" user "B.Adhesive")
		(13 "F.Paste" user "Package Geometry/Pastemask Top")
		(15 "B.Paste" user "Package Geometry/Pastemask Bottom")
		(5 "F.SilkS" user "Ref Des/Silkscreen Top")
		(7 "B.SilkS" user "Ref Des/Silkscreen Bottom")
		(1 "F.Mask" user "Board Geometry/Soldermask Top")
		(3 "B.Mask" user "Board Geometry/Soldermask Bottom")
		(17 "Dwgs.User" user "User.Drawings")
		(19 "Cmts.User" user "User.Comments")
		(21 "Eco1.User" user "User.Eco1")
		(23 "Eco2.User" user "User.Eco2")
		(25 "Edge.Cuts" user "Board Geometry/Outline")
		(27 "Margin" user)
		(31 "F.CrtYd" user "Package Geometry/Place Bound Top")
		(29 "B.CrtYd" user "Package Geometry/Place Bound Bottom")
		(35 "F.Fab" user "Ref Des/Assembly Top")
		(33 "B.Fab" user "Ref Des/Assembly Bottom")
	)
	(footprint ""
		(layer "F.Cu")
		(at 91.313 -423.164)
		(property "Reference" "R9070"
			(at 0 0 0)
			(layer "F.SilkS")
			(hide yes)
			(effects
				(font
					(size 1.27 1.27)
				)
			)
		)
		(property "Value" "27R2F-GP"
			(at 0.064008 -3.993896 0)
			(unlocked yes)
			(layer "F.Fab")
			(hide yes)
			(effects
				(font
					(size 1.016 1.016)
					(thickness 0.1524)
				)
			)
		)
		(property "Device Type" "R402H16"
			(at 0.064008 -5.517896 0)
			(unlocked yes)
			(layer "F.Fab")
			(hide yes)
			(effects
				(font
					(size 1.016 1.016)
					(thickness 0.1524)
				)
			)
		)
		(duplicate_pad_numbers_are_jumpers no)
		(fp_line
			(start -0.508 -0.9398)
			(end -0.508 0.9398)
			(stroke
				(width 0.1524)
				(type default)
			)
			(layer "F.SilkS")
		)
		(fp_line
			(start 0.508 -0.9398)
			(end -0.508 -0.9398)
			(stroke
				(width 0.1524)
				(type default)
			)
			(layer "F.SilkS")
		)
		(fp_rect
			(start -0.508 0.9398)
			(end 0.508 -0.9398)
			(stroke
				(width 0)
				(type default)
			)
			(fill no)
			(layer "F.CrtYd")
		)
		(fp_rect
			(start -0.508 0.9398)
			(end 0.508 -0.9398)
			(stroke
				(width 0)
				(type default)
			)
			(fill no)
			(layer "F.Fab")
		)
		(pad "1" smd custom
			(at 0 -0.4445)
			(size 0.1397 0.1397)
			(layers "F.Cu" "F.Mask" "F.Paste")
			(net "PE_CLK_100M_DR10_1_R_N")
			(options
				(clearance outline)
				(anchor circle)
			)
			(primitives
				(gr_poly
					(pts
						(arc
							(start -0.1778 -0.2794)
							(mid -0.249642 -0.249642)
							(end -0.2794 -0.1778)
						)
						(arc
							(start -0.2794 0.1778)
							(mid -0.249642 0.249642)
							(end -0.1778 0.2794)
						)
						(arc
							(start 0.1778 0.2794)
							(mid 0.249642 0.249642)
							(end 0.2794 0.1778)
						)
						(arc
							(start 0.2794 -0.1778)
							(mid 0.249642 -0.249642)
							(end 0.1778 -0.2794)
						)
					)
					(width 0)
					(fill yes)
				)
			)
		)
		(pad "2" smd custom
			(at 0 0.4445)
			(size 0.1397 0.1397)
			(layers "F.Cu" "F.Mask" "F.Paste")
			(net "PE_CLK100M_DR10_1_N")
			(options
				(clearance outline)
				(anchor circle)
			)
			(primitives
				(gr_poly
					(pts
						(arc
							(start -0.1778 -0.2794)
							(mid -0.249642 -0.249642)
							(end -0.2794 -0.1778)
						)
						(arc
							(start -0.2794 0.1778)
							(mid -0.249642 0.249642)
							(end -0.1778 0.2794)
						)
						(arc
							(start 0.1778 0.2794)
							(mid 0.249642 0.249642)
							(end 0.2794 0.1778)
						)
						(arc
							(start 0.2794 -0.1778)
							(mid 0.249642 -0.249642)
							(end 0.1778 -0.2794)
						)
					)
					(width 0)
					(fill yes)
				)
			)
		)
	)
	(footprint ""
		(layer "F.Cu")
		(at 16.55953 -257.158744 90)
		(property "Reference" "R9952"
			(at 0 0 90)
			(layer "F.SilkS")
			(hide yes)
			(effects
				(font
					(size 1.27 1.27)
				)
			)
		)
		(property "Value" "4K7R2J-2-GP"
			(at 0.064008 -3.993896 90)
			(unlocked yes)
			(layer "F.Fab")
			(hide yes)
			(effects
				(font
					(size 1.016 1.016)
					(thickness 0.1524)
				)
			)
		)
		(property "Device Type" "R402H16"
			(at 0.064008 -5.517896 90)
			(unlocked yes)
			(layer "F.Fab")
			(hide yes)
			(effects
				(font
					(size 1.016 1.016)
					(thickness 0.1524)
				)
			)
		)
		(duplicate_pad_numbers_are_jumpers no)
		(fp_line
			(start 0.508 -0.9398)
			(end -0.508 -0.9398)
			(stroke
				(width 0.1524)
				(type default)
			)
			(layer "F.SilkS")
		)
		(fp_line
			(start -0.508 -0.9398)
			(end -0.508 0.9398)
			(stroke
				(width 0.1524)
				(type default)
			)
			(layer "F.SilkS")
		)
		(fp_rect
			(start -0.508 0.9398)
			(end 0.508 -0.9398)
			(stroke
				(width 0)
				(type default)
			)
			(fill no)
			(layer "F.CrtYd")
		)
		(fp_rect
			(start -0.508 0.9398)
			(end 0.508 -0.9398)
			(stroke
				(width 0)
				(type default)
			)
			(fill no)
			(layer "F.Fab")
		)
		(pad "1" smd custom
			(at 0 -0.4445 90)
			(size 0.1397 0.1397)
			(layers "F.Cu" "F.Mask" "F.Paste")
			(net "P3V3")
			(options
				(clearance outline)
				(anchor circle)
			)
			(primitives
				(gr_poly
					(pts
						(arc
							(start -0.1778 -0.2794)
							(mid -0.249642 -0.249642)
							(end -0.2794 -0.1778)
						)
						(arc
							(start -0.2794 0.1778)
							(mid -0.249642 0.249642)
							(end -0.1778 0.2794)
						)
						(arc
							(start 0.1778 0.2794)
							(mid 0.249642 0.249642)
							(end 0.2794 0.1778)
						)
						(arc
							(start 0.2794 -0.1778)
							(mid 0.249642 -0.249642)
							(end 0.1778 -0.2794)
						)
					)
					(width 0)
					(fill yes)
				)
			)
		)
		(pad "2" smd custom
			(at 0 0.4445 90)
			(size 0.1397 0.1397)
			(layers "F.Cu" "F.Mask" "F.Paste")
			(net "SSD_ACT_DR12_MOS_N")
			(options
				(clearance outline)
				(anchor circle)
			)
			(primitives
				(gr_poly
					(pts
						(arc
							(start -0.1778 -0.2794)
							(mid -0.249642 -0.249642)
							(end -0.2794 -0.1778)
						)
						(arc
							(start -0.2794 0.1778)
							(mid -0.249642 0.249642)
							(end -0.1778 0.2794)
						)
						(arc
							(start 0.1778 0.2794)
							(mid 0.249642 0.249642)
							(end 0.2794 0.1778)
						)
						(arc
							(start 0.2794 -0.1778)
							(mid 0.249642 -0.249642)
							(end 0.1778 -0.2794)
						)
					)
					(width 0)
					(fill yes)
				)
			)
		)
	)
	(footprint ""
		(layer "F.Cu")
		(at 82.931 -307.34 90)
		(property "Reference" "SR949"
			(at 0 0 90)
			(layer "F.SilkS")
			(hide yes)
			(effects
				(font
					(size 1.27 1.27)
				)
			)
		)
		(property "Value" "4K7R2F-GP"
			(at 0.064008 -3.993896 90)
			(unlocked yes)
			(layer "F.Fab")
			(hide yes)
			(effects
				(font
					(size 1.016 1.016)
					(thickness 0.1524)
				)
			)
		)
		(property "Device Type" "R402H16"
			(at 0.064008 -5.517896 90)
			(unlocked yes)
			(layer "F.Fab")
			(hide yes)
			(effects
				(font
					(size 1.016 1.016)
					(thickness 0.1524)
				)
			)
		)
		(duplicate_pad_numbers_are_jumpers no)
		(fp_line
			(start 0.508 -0.9398)
			(end -0.508 -0.9398)
			(stroke
				(width 0.1524)
				(type default)
			)
			(layer "F.SilkS")
		)
		(fp_line
			(start -0.508 -0.9398)
			(end -0.508 0.9398)
			(stroke
				(width 0.1524)
				(type default)
			)
			(layer "F.SilkS")
		)
		(fp_rect
			(start -0.508 0.9398)
			(end 0.508 -0.9398)
			(stroke
				(width 0)
				(type default)
			)
			(fill no)
			(layer "F.CrtYd")
		)
		(fp_rect
			(start -0.508 0.9398)
			(end 0.508 -0.9398)
			(stroke
				(width 0)
				(type default)
			)
			(fill no)
			(layer "F.Fab")
		)
		(pad "1" smd custom
			(at 0 -0.4445 90)
			(size 0.1397 0.1397)
			(layers "F.Cu" "F.Mask" "F.Paste")
			(net "VDD_DIFF_2")
			(options
				(clearance outline)
				(anchor circle)
			)
			(primitives
				(gr_poly
					(pts
						(arc
							(start -0.1778 -0.2794)
							(mid -0.249642 -0.249642)
							(end -0.2794 -0.1778)
						)
						(arc
							(start -0.2794 0.1778)
							(mid -0.249642 0.249642)
							(end -0.1778 0.2794)
						)
						(arc
							(start 0.1778 0.2794)
							(mid 0.249642 0.249642)
							(end 0.2794 0.1778)
						)
						(arc
							(start 0.2794 -0.1778)
							(mid 0.249642 -0.249642)
							(end 0.1778 -0.2794)
						)
					)
					(width 0)
					(fill yes)
				)
			)
		)
		(pad "2" smd custom
			(at 0 0.4445 90)
			(size 0.1397 0.1397)
			(layers "F.Cu" "F.Mask" "F.Paste")
			(net "P3V3_PG")
			(options
				(clearance outline)
				(anchor circle)
			)
			(primitives
				(gr_poly
					(pts
						(arc
							(start -0.1778 -0.2794)
							(mid -0.249642 -0.249642)
							(end -0.2794 -0.1778)
						)
						(arc
							(start -0.2794 0.1778)
							(mid -0.249642 0.249642)
							(end -0.1778 0.2794)
						)
						(arc
							(start 0.1778 0.2794)
							(mid 0.249642 0.249642)
							(end 0.2794 0.1778)
						)
						(arc
							(start 0.2794 -0.1778)
							(mid 0.249642 -0.249642)
							(end 0.1778 -0.2794)
						)
					)
					(width 0)
					(fill yes)
				)
			)
		)
	)
	(footprint ""
		(layer "F.Cu")
		(at 52.324 -141.986 90)
		(property "Reference" "Q68"
			(at 0 0 90)
			(layer "F.SilkS")
			(hide yes)
			(effects
				(font
					(size 1.27 1.27)
				)
			)
		)
		(property "Value" "2N7002A-7-GP"
			(at 0.127 -8.9662 90)
			(unlocked yes)
			(layer "F.Fab")
			(hide yes)
			(effects
				(font
					(size 1.016 1.016)
					(thickness 0.1524)
				)
			)
		)
		(property "Device Type" "SOT23DGS2D4H48"
			(at 0.127 -10.4902 90)
			(unlocked yes)
			(layer "F.Fab")
			(hide yes)
			(effects
				(font
					(size 1.016 1.016)
					(thickness 0.1524)
				)
			)
		)
		(duplicate_pad_numbers_are_jumpers no)
		(fp_line
			(start 1.651 -1.778)
			(end -1.651 -1.778)
			(stroke
				(width 0.1524)
				(type default)
			)
			(layer "F.SilkS")
		)
		(fp_line
			(start -1.651 -1.778)
			(end -1.651 1.778)
			(stroke
				(width 0.1524)
				(type default)
			)
			(layer "F.SilkS")
		)
		(fp_line
			(start 1.651 1.778)
			(end 1.651 -1.778)
			(stroke
				(width 0.1524)
				(type default)
			)
			(layer "F.SilkS")
		)
		(fp_line
			(start -1.651 1.778)
			(end 1.651 1.778)
			(stroke
				(width 0.1524)
				(type default)
			)
			(layer "F.SilkS")
		)
		(fp_poly
			(pts
				(xy -1.778 1.8796) (xy -1.778 -1.8796) (xy 1.778 -1.8796) (xy 1.778 1.8796)
			)
			(stroke
				(width 0)
				(type default)
			)
			(fill no)
			(layer "F.CrtYd")
		)
		(fp_poly
			(pts
				(xy -1.778 1.8796) (xy -1.778 -1.8796) (xy 1.778 -1.8796) (xy 1.778 1.8796)
			)
			(stroke
				(width 0)
				(type default)
			)
			(fill no)
			(layer "F.Fab")
		)
		(pad "D" smd custom
			(at 0 -0.9525 90)
			(size 0.1905 0.1905)
			(layers "F.Cu" "F.Mask" "F.Paste")
			(net "SSD_ACT_DR8_MOS_N")
			(options
				(clearance outline)
				(anchor circle)
			)
			(primitives
				(gr_poly
					(pts
						(arc
							(start -0.1778 0.5715)
							(mid -0.321484 0.511984)
							(end -0.381 0.3683)
						)
						(arc
							(start -0.381 -0.3683)
							(mid -0.321484 -0.511984)
							(end -0.1778 -0.5715)
						)
						(arc
							(start 0.1778 -0.5715)
							(mid 0.321484 -0.511984)
							(end 0.381 -0.3683)
						)
						(arc
							(start 0.381 0.3683)
							(mid 0.321484 0.511984)
							(end 0.1778 0.5715)
						)
					)
					(width 0)
					(fill yes)
				)
			)
		)
		(pad "G" smd custom
			(at -0.98425 0.9525 90)
			(size 0.1905 0.1905)
			(layers "F.Cu" "F.Mask" "F.Paste")
			(net "ATTN_LED_DR8_AND_R")
			(options
				(clearance outline)
				(anchor circle)
			)
			(primitives
				(gr_poly
					(pts
						(arc
							(start -0.1778 0.5715)
							(mid -0.321484 0.511984)
							(end -0.381 0.3683)
						)
						(arc
							(start -0.381 -0.3683)
							(mid -0.321484 -0.511984)
							(end -0.1778 -0.5715)
						)
						(arc
							(start 0.1778 -0.5715)
							(mid 0.321484 -0.511984)
							(end 0.381 -0.3683)
						)
						(arc
							(start 0.381 0.3683)
							(mid 0.321484 0.511984)
							(end 0.1778 0.5715)
						)
					)
					(width 0)
					(fill yes)
				)
			)
		)
		(pad "S" smd custom
			(at 0.98425 0.9525 90)
			(size 0.1905 0.1905)
			(layers "F.Cu" "F.Mask" "F.Paste")
			(net "SSD_ACT_DR8_R")
			(options
				(clearance outline)
				(anchor circle)
			)
			(primitives
				(gr_poly
					(pts
						(arc
							(start -0.1778 0.5715)
							(mid -0.321484 0.511984)
							(end -0.381 0.3683)
						)
						(arc
							(start -0.381 -0.3683)
							(mid -0.321484 -0.511984)
							(end -0.1778 -0.5715)
						)
						(arc
							(start 0.1778 -0.5715)
							(mid 0.321484 -0.511984)
							(end 0.381 -0.3683)
						)
						(arc
							(start 0.381 0.3683)
							(mid 0.321484 0.511984)
							(end 0.1778 0.5715)
						)
					)
					(width 0)
					(fill yes)
				)
			)
		)
	)
	(footprint ""
		(layer "F.Cu")
		(at 19.115024 -402.68525 180)
		(property "Reference" "R9819"
			(at 0 0 180)
			(layer "F.SilkS")
			(hide yes)
			(effects
				(font
					(size 1.27 1.27)
				)
			)
		)
		(property "Value" "1KR2J-1-GP"
			(at 0.064008 -3.993896 180)
			(unlocked yes)
			(layer "F.Fab")
			(hide yes)
			(effects
				(font
					(size 1.016 1.016)
					(thickness 0.1524)
				)
			)
		)
		(property "Device Type" "R402H16"
			(at 0.064008 -5.517896 180)
			(unlocked yes)
			(layer "F.Fab")
			(hide yes)
			(effects
				(font
					(size 1.016 1.016)
					(thickness 0.1524)
				)
			)
		)
		(duplicate_pad_numbers_are_jumpers no)
		(fp_line
			(start 0.508 -0.9398)
			(end -0.508 -0.9398)
			(stroke
				(width 0.1524)
				(type default)
			)
			(layer "F.SilkS")
		)
		(fp_line
			(start -0.508 -0.9398)
			(end -0.508 0.9398)
			(stroke
				(width 0.1524)
				(type default)
			)
			(layer "F.SilkS")
		)
		(fp_rect
			(start -0.508 0.9398)
			(end 0.508 -0.9398)
			(stroke
				(width 0)
				(type default)
			)
			(fill no)
			(layer "F.CrtYd")
		)
		(fp_rect
			(start -0.508 0.9398)
			(end 0.508 -0.9398)
			(stroke
				(width 0)
				(type default)
			)
			(fill no)
			(layer "F.Fab")
		)
		(pad "1" smd custom
			(at 0 -0.4445 180)
			(size 0.1397 0.1397)
			(layers "F.Cu" "F.Mask" "F.Paste")
			(net "SSD6_PWREN")
			(options
				(clearance outline)
				(anchor circle)
			)
			(primitives
				(gr_poly
					(pts
						(arc
							(start -0.1778 -0.2794)
							(mid -0.249642 -0.249642)
							(end -0.2794 -0.1778)
						)
						(arc
							(start -0.2794 0.1778)
							(mid -0.249642 0.249642)
							(end -0.1778 0.2794)
						)
						(arc
							(start 0.1778 0.2794)
							(mid 0.249642 0.249642)
							(end 0.2794 0.1778)
						)
						(arc
							(start 0.2794 -0.1778)
							(mid 0.249642 -0.249642)
							(end 0.1778 -0.2794)
						)
					)
					(width 0)
					(fill yes)
				)
			)
		)
		(pad "2" smd custom
			(at 0 0.4445 180)
			(size 0.1397 0.1397)
			(layers "F.Cu" "F.Mask" "F.Paste")
			(net "SSD6_PWREN_R")
			(options
				(clearance outline)
				(anchor circle)
			)
			(primitives
				(gr_poly
					(pts
						(arc
							(start -0.1778 -0.2794)
							(mid -0.249642 -0.249642)
							(end -0.2794 -0.1778)
						)
						(arc
							(start -0.2794 0.1778)
							(mid -0.249642 0.249642)
							(end -0.1778 0.2794)
						)
						(arc
							(start 0.1778 0.2794)
							(mid 0.249642 0.249642)
							(end 0.2794 0.1778)
						)
						(arc
							(start 0.2794 -0.1778)
							(mid 0.249642 -0.249642)
							(end 0.1778 -0.2794)
						)
					)
					(width 0)
					(fill yes)
				)
			)
		)
	)
	(footprint ""
		(layer "F.Cu")
		(at 25.2984 -105.791)
		(property "Reference" "PC1210"
			(at 0 0 0)
			(layer "F.SilkS")
			(hide yes)
			(effects
				(font
					(size 1.27 1.27)
				)
			)
		)
		(property "Value" "SC22U25V6KX-GP-U"
			(at -2.860802 -5.279644 0)
			(unlocked yes)
			(layer "F.Fab")
			(hide yes)
			(effects
				(font
					(size 1.016 1.016)
					(thickness 0.1524)
				)
			)
		)
		(property "Device Type" "C1206-TO0D3H75"
			(at -2.860802 -6.803644 0)
			(unlocked yes)
			(layer "F.Fab")
			(hide yes)
			(effects
				(font
					(size 1.016 1.016)
					(thickness 0.1524)
				)
			)
		)
		(duplicate_pad_numbers_are_jumpers no)
		(fp_line
			(start -1.3081 -2.3749)
			(end 1.3081 -2.3749)
			(stroke
				(width 0.1524)
				(type default)
			)
			(layer "F.SilkS")
		)
		(fp_line
			(start -1.3081 2.3749)
			(end -1.3081 -2.3749)
			(stroke
				(width 0.1524)
				(type default)
			)
			(layer "F.SilkS")
		)
		(fp_line
			(start 1.3081 -2.3749)
			(end 1.3081 2.3749)
			(stroke
				(width 0.1524)
				(type default)
			)
			(layer "F.SilkS")
		)
		(fp_line
			(start 1.3081 2.3749)
			(end -1.3081 2.3749)
			(stroke
				(width 0.1524)
				(type default)
			)
			(layer "F.SilkS")
		)
		(fp_rect
			(start -0.8001 1.6002)
			(end 0.8001 -1.6002)
			(stroke
				(width 0)
				(type default)
			)
			(fill no)
			(layer "F.CrtYd")
		)
		(fp_poly
			(pts
				(xy -1.5621 2.4511) (xy -1.5621 1.6002) (xy 0.8001 1.6002) (xy 0.8001 -1.6002) (xy -0.8001 -1.6002)
				(xy -0.8001 1.5875) (xy -1.5621 1.5875) (xy -1.5621 -2.4511) (xy 1.5621 -2.4511) (xy 1.5621 2.4511)
			)
			(stroke
				(width 0)
				(type default)
			)
			(fill no)
			(layer "F.CrtYd")
		)
		(fp_rect
			(start -1.5621 2.4511)
			(end 1.5621 -2.4511)
			(stroke
				(width 0)
				(type default)
			)
			(fill no)
			(layer "F.Fab")
		)
		(pad "1" smd rect
			(at 0 -1.392936)
			(size 2.1082 1.4478)
			(layers "F.Cu" "F.Mask" "F.Paste")
			(net "P12V_SSD13")
		)
		(pad "2" smd rect
			(at 0 1.392936)
			(size 2.1082 1.4478)
			(layers "F.Cu" "F.Mask" "F.Paste")
			(net "GND")
		)
	)
	(footprint ""
		(layer "F.Cu")
		(at 40.259 -204.724)
		(property "Reference" "R9859"
			(at 0 0 0)
			(layer "F.SilkS")
			(hide yes)
			(effects
				(font
					(size 1.27 1.27)
				)
			)
		)
		(property "Value" "1KR2J-1-GP"
			(at 0.064008 -3.993896 0)
			(unlocked yes)
			(layer "F.Fab")
			(hide yes)
			(effects
				(font
					(size 1.016 1.016)
					(thickness 0.1524)
				)
			)
		)
		(property "Device Type" "R402H16"
			(at 0.064008 -5.517896 0)
			(unlocked yes)
			(layer "F.Fab")
			(hide yes)
			(effects
				(font
					(size 1.016 1.016)
					(thickness 0.1524)
				)
			)
		)
		(duplicate_pad_numbers_are_jumpers no)
		(fp_line
			(start -0.508 -0.9398)
			(end -0.508 0.9398)
			(stroke
				(width 0.1524)
				(type default)
			)
			(layer "F.SilkS")
		)
		(fp_line
			(start 0.508 -0.9398)
			(end -0.508 -0.9398)
			(stroke
				(width 0.1524)
				(type default)
			)
			(layer "F.SilkS")
		)
		(fp_rect
			(start -0.508 0.9398)
			(end 0.508 -0.9398)
			(stroke
				(width 0)
				(type default)
			)
			(fill no)
			(layer "F.CrtYd")
		)
		(fp_rect
			(start -0.508 0.9398)
			(end 0.508 -0.9398)
			(stroke
				(width 0)
				(type default)
			)
			(fill no)
			(layer "F.Fab")
		)
		(pad "1" smd custom
			(at 0 -0.4445)
			(size 0.1397 0.1397)
			(layers "F.Cu" "F.Mask" "F.Paste")
			(net "SSD12_PWREN")
			(options
				(clearance outline)
				(anchor circle)
			)
			(primitives
				(gr_poly
					(pts
						(arc
							(start -0.1778 -0.2794)
							(mid -0.249642 -0.249642)
							(end -0.2794 -0.1778)
						)
						(arc
							(start -0.2794 0.1778)
							(mid -0.249642 0.249642)
							(end -0.1778 0.2794)
						)
						(arc
							(start 0.1778 0.2794)
							(mid 0.249642 0.249642)
							(end 0.2794 0.1778)
						)
						(arc
							(start 0.2794 -0.1778)
							(mid 0.249642 -0.249642)
							(end 0.1778 -0.2794)
						)
					)
					(width 0)
					(fill yes)
				)
			)
		)
		(pad "2" smd custom
			(at 0 0.4445)
			(size 0.1397 0.1397)
			(layers "F.Cu" "F.Mask" "F.Paste")
			(net "SSD12_PWREN_R")
			(options
				(clearance outline)
				(anchor circle)
			)
			(primitives
				(gr_poly
					(pts
						(arc
							(start -0.1778 -0.2794)
							(mid -0.249642 -0.249642)
							(end -0.2794 -0.1778)
						)
						(arc
							(start -0.2794 0.1778)
							(mid -0.249642 0.249642)
							(end -0.1778 0.2794)
						)
						(arc
							(start 0.1778 0.2794)
							(mid 0.249642 0.249642)
							(end 0.2794 0.1778)
						)
						(arc
							(start 0.2794 -0.1778)
							(mid 0.249642 -0.249642)
							(end 0.1778 -0.2794)
						)
					)
					(width 0)
					(fill yes)
				)
			)
		)
	)
)
